# S9S_MB_2U (Grand Teton) — schematic netlist excerpt (pin names and nets, part order shuffled) for the footprints in the layout excerpt that follows; sources: Cadence DE-HDL packaged netlist, KiCad conversion of 03242023_DA0F0TMBIJ0_F0T_Motherboard_J_brd_V01_OCP.brd

R896  Q_RES  33.2 1% CHIP  pkg 0402LF  page 114 : A = PWRGD_CHB_CPU1_DIMM2 ; B = PWRGD_FAIL_CPU1_AB
R2477  Q_RES  33.2 1% CHIP  pkg 0402LF  page 235 : A = SMB_PEHPCPU0_LVC3_SCL_R0 ; B = SMB_PEHPCPU0_LVC3_SCL

(kicad_pcb
	(version 20260206)
	(generator "pcbnew")
	(generator_version "10.0")
	(general
		(thickness 1.6)
		(legacy_teardrops no)
	)
	(paper "A4")
	(title_block
		(title "03242023_DA0F0TMBIJ0_F0T_Motherboard_J_brd_V01_OCP.brd")
		(comment 1 "Grand Teton / footprints 5366-5367 of 6105")
	)
	(layers
		(0 "F.Cu" signal "TOP")
		(4 "In1.Cu" signal "GND")
		(6 "In2.Cu" signal "IN1")
		(8 "In3.Cu" signal "GND1")
		(10 "In4.Cu" signal "IN2")
		(12 "In5.Cu" signal "GND2")
		(14 "In6.Cu" signal "IN3")
		(16 "In7.Cu" signal "GND3")
		(18 "In8.Cu" signal "VCC")
		(20 "In9.Cu" signal "VCC1")
		(22 "In10.Cu" signal "GND4")
		(24 "In11.Cu" signal "IN4")
		(26 "In12.Cu" signal "GND5")
		(28 "In13.Cu" signal "IN5")
		(30 "In14.Cu" signal "GND6")
		(32 "In15.Cu" signal "IN6")
		(34 "In16.Cu" signal "GND7")
		(2 "B.Cu" signal "BOTTOM")
		(9 "F.Adhes" user "F.Adhesive")
		(11 "B.Adhes" user "B.Adhesive")
		(13 "F.Paste" user "Package Geometry/Pastemask Top")
		(15 "B.Paste" user "Package Geometry/Pastemask Bottom")
		(5 "F.SilkS" user "Ref Des/Silkscreen Top")
		(7 "B.SilkS" user "Ref Des/Silkscreen Bottom")
		(1 "F.Mask" user "Board Geometry/Soldermask Top")
		(3 "B.Mask" user "Board Geometry/Soldermask Bottom")
		(17 "Dwgs.User" user "User.Drawings")
		(19 "Cmts.User" user "User.Comments")
		(21 "Eco1.User" user "User.Eco1")
		(23 "Eco2.User" user "User.Eco2")
		(25 "Edge.Cuts" user "Board Geometry/Outline")
		(27 "Margin" user)
		(31 "F.CrtYd" user "Package Geometry/Place Bound Top")
		(29 "B.CrtYd" user "Package Geometry/Place Bound Bottom")
		(35 "F.Fab" user "Ref Des/Assembly Top")
		(33 "B.Fab" user "Ref Des/Assembly Bottom")
	)
	(footprint ""
		(layer "B.Cu")
		(at 370.539772 -184.400952 90)
		(property "Reference" "R2477"
			(at 0 0 90)
			(layer "B.SilkS")
			(hide yes)
			(effects
				(font
					(size 1.27 1.27)
				)
				(justify mirror)
			)
		)
		(property "Value" ""
			(at 0 0 90)
			(layer "B.Fab")
			(effects
				(font
					(size 1.27 1.27)
				)
				(justify mirror)
			)
		)
		(duplicate_pad_numbers_are_jumpers no)
		(fp_line
			(start 0.7874 -0.4064)
			(end -0.7874 -0.4064)
			(stroke
				(width 0.1524)
				(type default)
			)
			(layer "B.SilkS")
		)
		(fp_line
			(start -0.7874 -0.4064)
			(end -0.7874 0.4064)
			(stroke
				(width 0.1524)
				(type default)
			)
			(layer "B.SilkS")
		)
		(fp_line
			(start 0.7874 0.4064)
			(end 0.7874 -0.4064)
			(stroke
				(width 0.1524)
				(type default)
			)
			(layer "B.SilkS")
		)
		(fp_line
			(start -0.7874 0.4064)
			(end 0.7874 0.4064)
			(stroke
				(width 0.1524)
				(type default)
			)
			(layer "B.SilkS")
		)
		(fp_line
			(start 0.67945 -0.305054)
			(end 0.12065 -0.305054)
			(stroke
				(width 0.1)
				(type default)
			)
			(layer "B.Fab")
		)
		(fp_line
			(start 0.12065 -0.305054)
			(end 0.12065 -0.2794)
			(stroke
				(width 0.1)
				(type default)
			)
			(layer "B.Fab")
		)
		(fp_line
			(start -0.12065 -0.3048)
			(end -0.67945 -0.3048)
			(stroke
				(width 0.1)
				(type default)
			)
			(layer "B.Fab")
		)
		(fp_line
			(start -0.67945 -0.3048)
			(end -0.67945 0.3048)
			(stroke
				(width 0.1)
				(type default)
			)
			(layer "B.Fab")
		)
		(fp_line
			(start 0.12065 -0.2794)
			(end -0.12065 -0.2794)
			(stroke
				(width 0.1)
				(type default)
			)
			(layer "B.Fab")
		)
		(fp_line
			(start -0.12065 -0.2794)
			(end -0.12065 -0.3048)
			(stroke
				(width 0.1)
				(type default)
			)
			(layer "B.Fab")
		)
		(fp_line
			(start 0.12065 0.2794)
			(end 0.12065 0.3048)
			(stroke
				(width 0.1)
				(type default)
			)
			(layer "B.Fab")
		)
		(fp_line
			(start -0.120396 0.2794)
			(end 0.12065 0.2794)
			(stroke
				(width 0.1)
				(type default)
			)
			(layer "B.Fab")
		)
		(fp_line
			(start 0.67945 0.3048)
			(end 0.67945 -0.305054)
			(stroke
				(width 0.1)
				(type default)
			)
			(layer "B.Fab")
		)
		(fp_line
			(start 0.12065 0.3048)
			(end 0.67945 0.3048)
			(stroke
				(width 0.1)
				(type default)
			)
			(layer "B.Fab")
		)
		(fp_line
			(start -0.120396 0.3048)
			(end -0.120396 0.2794)
			(stroke
				(width 0.1)
				(type default)
			)
			(layer "B.Fab")
		)
		(fp_line
			(start -0.67945 0.3048)
			(end -0.120396 0.3048)
			(stroke
				(width 0.1)
				(type default)
			)
			(layer "B.Fab")
		)
		(pad "1" smd circle
			(at 0.40005 0 270)
			(size 0 0)
			(layers "B.Cu" "B.Mask" "B.Paste")
			(net "SMB_PEHPCPU0_LVC3_SCL_R0")
		)
		(pad "2" smd circle
			(at -0.40005 0 270)
			(size 0 0)
			(layers "B.Cu" "B.Mask" "B.Paste")
			(net "SMB_PEHPCPU0_LVC3_SCL")
		)
	)
	(footprint ""
		(layer "B.Cu")
		(at 49.936146 -319.268856 180)
		(property "Reference" "R896"
			(at 0 0 0)
			(layer "B.SilkS")
			(hide yes)
			(effects
				(font
					(size 1.27 1.27)
				)
				(justify mirror)
			)
		)
		(property "Value" ""
			(at 0 0 0)
			(layer "B.Fab")
			(effects
				(font
					(size 1.27 1.27)
				)
				(justify mirror)
			)
		)
		(duplicate_pad_numbers_are_jumpers no)
		(fp_line
			(start 0.7874 0.4064)
			(end 0.7874 -0.4064)
			(stroke
				(width 0.1524)
				(type default)
			)
			(layer "B.SilkS")
		)
		(fp_line
			(start 0.7874 -0.4064)
			(end -0.7874 -0.4064)
			(stroke
				(width 0.1524)
				(type default)
			)
			(layer "B.SilkS")
		)
		(fp_line
			(start -0.7874 0.4064)
			(end 0.7874 0.4064)
			(stroke
				(width 0.1524)
				(type default)
			)
			(layer "B.SilkS")
		)
		(fp_line
			(start -0.7874 -0.4064)
			(end -0.7874 0.4064)
			(stroke
				(width 0.1524)
				(type default)
			)
			(layer "B.SilkS")
		)
		(fp_line
			(start 0.67945 0.3048)
			(end 0.67945 -0.305054)
			(stroke
				(width 0.1)
				(type default)
			)
			(layer "B.Fab")
		)
		(fp_line
			(start 0.67945 -0.305054)
			(end 0.12065 -0.305054)
			(stroke
				(width 0.1)
				(type default)
			)
			(layer "B.Fab")
		)
		(fp_line
			(start 0.12065 0.3048)
			(end 0.67945 0.3048)
			(stroke
				(width 0.1)
				(type default)
			)
			(layer "B.Fab")
		)
		(fp_line
			(start 0.12065 0.2794)
			(end 0.12065 0.3048)
			(stroke
				(width 0.1)
				(type default)
			)
			(layer "B.Fab")
		)
		(fp_line
			(start 0.12065 -0.2794)
			(end -0.12065 -0.2794)
			(stroke
				(width 0.1)
				(type default)
			)
			(layer "B.Fab")
		)
		(fp_line
			(start 0.12065 -0.305054)
			(end 0.12065 -0.2794)
			(stroke
				(width 0.1)
				(type default)
			)
			(layer "B.Fab")
		)
		(fp_line
			(start -0.120396 0.3048)
			(end -0.120396 0.2794)
			(stroke
				(width 0.1)
				(type default)
			)
			(layer "B.Fab")
		)
		(fp_line
			(start -0.120396 0.2794)
			(end 0.12065 0.2794)
			(stroke
				(width 0.1)
				(type default)
			)
			(layer "B.Fab")
		)
		(fp_line
			(start -0.12065 -0.2794)
			(end -0.12065 -0.3048)
			(stroke
				(width 0.1)
				(type default)
			)
			(layer "B.Fab")
		)
		(fp_line
			(start -0.12065 -0.3048)
			(end -0.67945 -0.3048)
			(stroke
				(width 0.1)
				(type default)
			)
			(layer "B.Fab")
		)
		(fp_line
			(start -0.67945 0.3048)
			(end -0.120396 0.3048)
			(stroke
				(width 0.1)
				(type default)
			)
			(layer "B.Fab")
		)
		(fp_line
			(start -0.67945 -0.3048)
			(end -0.67945 0.3048)
			(stroke
				(width 0.1)
				(type default)
			)
			(layer "B.Fab")
		)
		(pad "1" smd circle
			(at 0.40005 0)
			(size 0 0)
			(layers "B.Cu" "B.Mask" "B.Paste")
			(net "PWRGD_CHB_CPU1_DIMM2")
		)
		(pad "2" smd circle
			(at -0.40005 0)
			(size 0 0)
			(layers "B.Cu" "B.Mask" "B.Paste")
			(net "PWRGD_FAIL_CPU1_AB")
		)
	)
)
